# T6G (Grand Teton) — schematic netlist excerpt (pin names and nets, part order shuffled) for the footprints in the layout excerpt that follows; sources: Cadence DE-HDL packaged netlist, KiCad conversion of 04192023_DAF0TMB3IC0_F0TG_MB_C_brd_V02_OCP.brd

C7015  Q_CAPP  470UF 2.5V 20% SPCAP  pkg SMLF  page 301 : A = P0V9_CPU0_RT2_2A ; B = GND
R2706  Q_RES  0 5% CHIP  pkg 0402LF  page 248 : A = I3C_BMC_SWB_R_SDA ; B = I3C_BMC_SWB_BUF_R_SDA

(kicad_pcb
	(version 20260206)
	(generator "pcbnew")
	(generator_version "10.0")
	(general
		(thickness 1.6)
		(legacy_teardrops no)
	)
	(paper "A4")
	(title_block
		(title "04192023_DAF0TMB3IC0_F0TG_MB_C_brd_V02_OCP.brd")
		(comment 1 "Grand Teton / footprints 5679-5680 of 8354")
	)
	(layers
		(0 "F.Cu" signal "TOP")
		(4 "In1.Cu" signal "GND")
		(6 "In2.Cu" signal "IN1")
		(8 "In3.Cu" signal "GND1")
		(10 "In4.Cu" signal "IN2")
		(12 "In5.Cu" signal "GND2")
		(14 "In6.Cu" signal "IN3")
		(16 "In7.Cu" signal "GND3")
		(18 "In8.Cu" signal "VCC")
		(20 "In9.Cu" signal "VCC1")
		(22 "In10.Cu" signal "GND4")
		(24 "In11.Cu" signal "IN4")
		(26 "In12.Cu" signal "GND5")
		(28 "In13.Cu" signal "IN5")
		(30 "In14.Cu" signal "GND6")
		(32 "In15.Cu" signal "IN6")
		(34 "In16.Cu" signal "GND7")
		(2 "B.Cu" signal "BOTTOM")
		(9 "F.Adhes" user "F.Adhesive")
		(11 "B.Adhes" user "B.Adhesive")
		(13 "F.Paste" user "Package Geometry/Pastemask Top")
		(15 "B.Paste" user "Package Geometry/Pastemask Bottom")
		(5 "F.SilkS" user "Ref Des/Silkscreen Top")
		(7 "B.SilkS" user "Ref Des/Silkscreen Bottom")
		(1 "F.Mask" user "Board Geometry/Soldermask Top")
		(3 "B.Mask" user "Board Geometry/Soldermask Bottom")
		(17 "Dwgs.User" user "User.Drawings")
		(19 "Cmts.User" user "User.Comments")
		(21 "Eco1.User" user "User.Eco1")
		(23 "Eco2.User" user "User.Eco2")
		(25 "Edge.Cuts" user "Board Geometry/Outline")
		(27 "Margin" user)
		(31 "F.CrtYd" user "Package Geometry/Place Bound Top")
		(29 "B.CrtYd" user "Package Geometry/Place Bound Bottom")
		(35 "F.Fab" user "Ref Des/Assembly Top")
		(33 "B.Fab" user "Ref Des/Assembly Bottom")
	)
	(footprint ""
		(layer "B.Cu")
		(at 291.578538 -426.06087 -90)
		(property "Reference" "R2706"
			(at 0 0 90)
			(layer "B.SilkS")
			(hide yes)
			(effects
				(font
					(size 1.27 1.27)
				)
				(justify mirror)
			)
		)
		(property "Value" ""
			(at 0 0 90)
			(layer "B.Fab")
			(effects
				(font
					(size 1.27 1.27)
				)
				(justify mirror)
			)
		)
		(duplicate_pad_numbers_are_jumpers no)
		(fp_line
			(start -0.7874 0.4064)
			(end 0.7874 0.4064)
			(stroke
				(width 0.1524)
				(type default)
			)
			(layer "B.SilkS")
		)
		(fp_line
			(start 0.7874 0.4064)
			(end 0.7874 -0.4064)
			(stroke
				(width 0.1524)
				(type default)
			)
			(layer "B.SilkS")
		)
		(fp_line
			(start -0.7874 -0.4064)
			(end -0.7874 0.4064)
			(stroke
				(width 0.1524)
				(type default)
			)
			(layer "B.SilkS")
		)
		(fp_line
			(start 0.7874 -0.4064)
			(end -0.7874 -0.4064)
			(stroke
				(width 0.1524)
				(type default)
			)
			(layer "B.SilkS")
		)
		(fp_line
			(start -0.67945 0.3048)
			(end -0.120396 0.3048)
			(stroke
				(width 0.1)
				(type default)
			)
			(layer "B.Fab")
		)
		(fp_line
			(start -0.120396 0.3048)
			(end -0.120396 0.2794)
			(stroke
				(width 0.1)
				(type default)
			)
			(layer "B.Fab")
		)
		(fp_line
			(start 0.12065 0.3048)
			(end 0.67945 0.3048)
			(stroke
				(width 0.1)
				(type default)
			)
			(layer "B.Fab")
		)
		(fp_line
			(start 0.67945 0.3048)
			(end 0.67945 -0.305054)
			(stroke
				(width 0.1)
				(type default)
			)
			(layer "B.Fab")
		)
		(fp_line
			(start -0.120396 0.2794)
			(end 0.12065 0.2794)
			(stroke
				(width 0.1)
				(type default)
			)
			(layer "B.Fab")
		)
		(fp_line
			(start 0.12065 0.2794)
			(end 0.12065 0.3048)
			(stroke
				(width 0.1)
				(type default)
			)
			(layer "B.Fab")
		)
		(fp_line
			(start -0.12065 -0.2794)
			(end -0.12065 -0.3048)
			(stroke
				(width 0.1)
				(type default)
			)
			(layer "B.Fab")
		)
		(fp_line
			(start 0.12065 -0.2794)
			(end -0.12065 -0.2794)
			(stroke
				(width 0.1)
				(type default)
			)
			(layer "B.Fab")
		)
		(fp_line
			(start -0.67945 -0.3048)
			(end -0.67945 0.3048)
			(stroke
				(width 0.1)
				(type default)
			)
			(layer "B.Fab")
		)
		(fp_line
			(start -0.12065 -0.3048)
			(end -0.67945 -0.3048)
			(stroke
				(width 0.1)
				(type default)
			)
			(layer "B.Fab")
		)
		(fp_line
			(start 0.12065 -0.305054)
			(end 0.12065 -0.2794)
			(stroke
				(width 0.1)
				(type default)
			)
			(layer "B.Fab")
		)
		(fp_line
			(start 0.67945 -0.305054)
			(end 0.12065 -0.305054)
			(stroke
				(width 0.1)
				(type default)
			)
			(layer "B.Fab")
		)
		(pad "1" smd circle
			(at 0.40005 0 90)
			(size 0 0)
			(layers "B.Cu" "B.Mask" "B.Paste")
			(net "I3C_BMC_SWB_R_SDA")
		)
		(pad "2" smd circle
			(at -0.40005 0 90)
			(size 0 0)
			(layers "B.Cu" "B.Mask" "B.Paste")
			(net "I3C_BMC_SWB_BUF_R_SDA")
		)
	)
	(footprint ""
		(layer "B.Cu")
		(at 408.124914 -389.49503 180)
		(property "Reference" "C7015"
			(at -1.360932 -3.149092 0)
			(unlocked yes)
			(layer "B.SilkS")
			(effects
				(font
					(size 0.7874 0.5842)
					(thickness 0.1524)
				)
				(justify left mirror)
			)
		)
		(property "Value" ""
			(at 0 0 0)
			(layer "B.Fab")
			(effects
				(font
					(size 1.27 1.27)
				)
				(justify mirror)
			)
		)
		(duplicate_pad_numbers_are_jumpers no)
		(fp_line
			(start 4.84378 -2.150618)
			(end 4.842256 2.163064)
			(stroke
				(width 0.1524)
				(type default)
			)
			(layer "B.SilkS")
		)
		(fp_line
			(start 4.84378 -2.150618)
			(end 4.53898 -2.150618)
			(stroke
				(width 0.1524)
				(type default)
			)
			(layer "B.SilkS")
		)
		(fp_line
			(start 4.83108 2.150364)
			(end 4.447794 2.149348)
			(stroke
				(width 0.1524)
				(type default)
			)
			(layer "B.SilkS")
		)
		(fp_line
			(start 4.69138 -2.150618)
			(end 4.692396 2.161032)
			(stroke
				(width 0.1524)
				(type default)
			)
			(layer "B.SilkS")
		)
		(fp_line
			(start 4.53898 2.15011)
			(end 4.53898 -2.15011)
			(stroke
				(width 0.1524)
				(type default)
			)
			(layer "B.SilkS")
		)
		(fp_line
			(start 4.53898 -2.15011)
			(end -4.53898 -2.15011)
			(stroke
				(width 0.1524)
				(type default)
			)
			(layer "B.SilkS")
		)
		(fp_line
			(start 4.53898 -2.150618)
			(end 4.539742 2.152142)
			(stroke
				(width 0.1524)
				(type default)
			)
			(layer "B.SilkS")
		)
		(fp_line
			(start -4.53898 2.15011)
			(end 4.53898 2.15011)
			(stroke
				(width 0.1524)
				(type default)
			)
			(layer "B.SilkS")
		)
		(fp_line
			(start -4.53898 -2.15011)
			(end -4.53898 2.15011)
			(stroke
				(width 0.1524)
				(type default)
			)
			(layer "B.SilkS")
		)
		(fp_line
			(start 3.64998 2.15011)
			(end 3.64998 -2.15011)
			(stroke
				(width 0.1)
				(type default)
			)
			(layer "B.Fab")
		)
		(fp_line
			(start 3.64998 -2.15011)
			(end -3.64998 -2.15011)
			(stroke
				(width 0.1)
				(type default)
			)
			(layer "B.Fab")
		)
		(fp_line
			(start -3.64998 2.15011)
			(end 3.64998 2.15011)
			(stroke
				(width 0.1)
				(type default)
			)
			(layer "B.Fab")
		)
		(fp_line
			(start -3.64998 -2.15011)
			(end -3.64998 2.15011)
			(stroke
				(width 0.1)
				(type default)
			)
			(layer "B.Fab")
		)
		(fp_text user "+"
			(at 4.444492 -3.049778 180)
			(unlocked yes)
			(layer "B.SilkS")
			(effects
				(font
					(size 1.905 1.4224)
					(thickness 0.1524)
				)
				(justify left mirror)
			)
		)
		(fp_text user "-"
			(at -2.781554 -2.878328 180)
			(unlocked yes)
			(layer "B.SilkS")
			(effects
				(font
					(size 1.905 1.4224)
					(thickness 0.1524)
				)
				(justify left mirror)
			)
		)
		(fp_text user "+"
			(at 6.214872 -0.337058 180)
			(unlocked yes)
			(layer "B.Fab")
			(effects
				(font
					(size 1.905 1.4224)
					(thickness 0.1524)
				)
				(justify left mirror)
			)
		)
		(fp_text user "-"
			(at -4.313174 -0.094488 180)
			(unlocked yes)
			(layer "B.Fab")
			(effects
				(font
					(size 1.905 1.4224)
					(thickness 0.1524)
				)
				(justify left mirror)
			)
		)
		(pad "1" smd rect
			(at 3.199892 0)
			(size 2.413 2.8194)
			(layers "B.Cu" "B.Mask" "B.Paste")
			(net "P0V9_CPU0_RT2_2A")
		)
		(pad "2" smd rect
			(at -3.199892 0)
			(size 2.413 2.8194)
			(layers "B.Cu" "B.Mask" "B.Paste")
			(net "GND")
		)
	)
)
